# TIMECARD (Time Appliance Project (Time Card)) — schematic netlist excerpt (pin names and nets, part order shuffled) for the footprints in the layout excerpt that follows; sources: Cadence DE-HDL packaged netlist, KiCad conversion of R4006-B0001-02_R01.brd

C218  CAPACITOR  0.1UF 10V 10%  pkg SMC_0402R_H022  page 14 : \1\ = XP1R0V_FPGA_MGTAVCC ; \2\ = SG
R479  RESISTOR  100KOHM 1%  pkg SMC_0402R_H016  page 24 : \1\ = FT4232_I2C_SDA ; \2\ = XP3R3V_FT4232

(kicad_pcb
	(version 20260206)
	(generator "pcbnew")
	(generator_version "10.0")
	(general
		(thickness 1.6)
		(legacy_teardrops no)
	)
	(paper "A4")
	(title_block
		(title "timecard-production-celestica-r4006 — R4006-B0001-02_R01.brd")
		(comment 1 "Time Appliance Project (Time Card) / footprints 746-747 of 1113")
	)
	(layers
		(0 "F.Cu" signal "TOP")
		(4 "In1.Cu" signal "L02_GND1")
		(6 "In2.Cu" signal "L03_SIG1")
		(8 "In3.Cu" signal "L04_GND2")
		(10 "In4.Cu" signal "L05_VCC1")
		(12 "In5.Cu" signal "L06_VCC2")
		(14 "In6.Cu" signal "L07_GND3")
		(16 "In7.Cu" signal "L08_SIG2")
		(18 "In8.Cu" signal "L09_GND4")
		(2 "B.Cu" signal "BOTTOM")
		(9 "F.Adhes" user "F.Adhesive")
		(11 "B.Adhes" user "B.Adhesive")
		(13 "F.Paste" user "Package Geometry/Pastemask Top")
		(15 "B.Paste" user "Package Geometry/Pastemask Bottom")
		(5 "F.SilkS" user "Ref Des/Silkscreen Top")
		(7 "B.SilkS" user "Ref Des/Silkscreen Bottom")
		(1 "F.Mask" user "Board Geometry/Soldermask Top")
		(3 "B.Mask" user "Board Geometry/Soldermask Bottom")
		(17 "Dwgs.User" user "User.Drawings")
		(19 "Cmts.User" user "User.Comments")
		(21 "Eco1.User" user "User.Eco1")
		(23 "Eco2.User" user "User.Eco2")
		(25 "Edge.Cuts" user "Board Geometry/Outline")
		(27 "Margin" user)
		(31 "F.CrtYd" user "Package Geometry/Place Bound Top")
		(29 "B.CrtYd" user "Package Geometry/Place Bound Bottom")
		(35 "F.Fab" user "Ref Des/Assembly Top")
		(33 "B.Fab" user "Ref Des/Assembly Bottom")
	)
	(footprint ""
		(layer "B.Cu")
		(at 101.847142 -39.323264 -90)
		(property "Reference" "C218"
			(at 1.268984 42.018712 270)
			(unlocked yes)
			(layer "B.SilkS")
			(effects
				(font
					(size 0.635 0.4064)
					(thickness 0.1524)
				)
				(justify mirror)
			)
		)
		(property "Value" "VAL*"
			(at 0 3.718306 270)
			(unlocked yes)
			(layer "B.Fab")
			(hide yes)
			(effects
				(font
					(size 0.7874 0.5842)
					(thickness 0.127)
				)
				(justify mirror)
			)
		)
		(property "Tolerance" "TOL*"
			(at 0 4.861306 270)
			(unlocked yes)
			(layer "Cmts.User")
			(hide yes)
			(effects
				(font
					(size 0.7874 0.5842)
					(thickness 0.127)
				)
				(justify mirror)
			)
		)
		(property "User Part Number" "PARTNUM*"
			(at 0 2.575306 270)
			(unlocked yes)
			(layer "Cmts.User")
			(hide yes)
			(effects
				(font
					(size 0.7874 0.5842)
					(thickness 0.127)
				)
				(justify mirror)
			)
		)
		(property "Device Type" "CAPACITOR-G105-0B104-CK,0.1UF,A"
			(at 0 1.432306 270)
			(unlocked yes)
			(layer "B.Fab")
			(hide yes)
			(effects
				(font
					(size 0.7874 0.5842)
					(thickness 0.127)
				)
				(justify mirror)
			)
		)
		(duplicate_pad_numbers_are_jumpers no)
		(fp_line
			(start -0.970026 0.4699)
			(end 0.970026 0.4699)
			(stroke
				(width 0.1)
				(type default)
			)
			(layer "B.SilkS")
		)
		(fp_line
			(start 0.970026 0.4699)
			(end 0.970026 -0.4699)
			(stroke
				(width 0.1)
				(type default)
			)
			(layer "B.SilkS")
		)
		(fp_line
			(start -0.970026 -0.4699)
			(end -0.970026 0.4699)
			(stroke
				(width 0.1)
				(type default)
			)
			(layer "B.SilkS")
		)
		(fp_line
			(start 0.970026 -0.4699)
			(end -0.970026 -0.4699)
			(stroke
				(width 0.1)
				(type default)
			)
			(layer "B.SilkS")
		)
		(fp_poly
			(pts
				(xy 0.970026 0.4699) (xy -0.970026 0.4699) (xy -0.970026 -0.4699) (xy 0.970026 -0.4699)
			)
			(stroke
				(width 0)
				(type default)
			)
			(fill no)
			(layer "B.CrtYd")
		)
		(fp_line
			(start -0.508 0.3048)
			(end 0.508 0.3048)
			(stroke
				(width 0.1)
				(type default)
			)
			(layer "B.Fab")
		)
		(fp_line
			(start 0.508 0.3048)
			(end 0.508 -0.3048)
			(stroke
				(width 0.1)
				(type default)
			)
			(layer "B.Fab")
		)
		(fp_line
			(start -0.508 -0.3048)
			(end -0.508 0.3048)
			(stroke
				(width 0.1)
				(type default)
			)
			(layer "B.Fab")
		)
		(fp_line
			(start 0.508 -0.3048)
			(end -0.508 -0.3048)
			(stroke
				(width 0.1)
				(type default)
			)
			(layer "B.Fab")
		)
		(pad "1" smd circle
			(at 0.500126 0 90)
			(size 0.635 0.635)
			(layers "B.Cu" "B.Mask" "B.Paste")
			(net "XP1R0V_FPGA_MGTAVCC")
		)
		(pad "2" smd circle
			(at -0.500126 0 90)
			(size 0.635 0.635)
			(layers "B.Cu" "B.Mask" "B.Paste")
			(net "SG")
		)
	)
	(footprint ""
		(layer "B.Cu")
		(at 18.415 -81.28 180)
		(property "Reference" "R479"
			(at -3.81 -0.42037 0)
			(unlocked yes)
			(layer "B.SilkS")
			(effects
				(font
					(size 0.7874 0.5842)
					(thickness 0.1524)
				)
				(justify mirror)
			)
		)
		(property "Value" "VAL*"
			(at -0.02032 2.13233 180)
			(unlocked yes)
			(layer "B.Fab")
			(hide yes)
			(effects
				(font
					(size 0.7874 0.5842)
					(thickness 0.1524)
				)
				(justify mirror)
			)
		)
		(property "Tolerance" "TOL*"
			(at -0.044704 3.05435 180)
			(unlocked yes)
			(layer "Cmts.User")
			(hide yes)
			(effects
				(font
					(size 0.7874 0.5842)
					(thickness 0.1524)
				)
				(justify mirror)
			)
		)
		(property "User Part Number" "PARTNUM*"
			(at -0.02032 4.024884 180)
			(unlocked yes)
			(layer "Cmts.User")
			(hide yes)
			(effects
				(font
					(size 0.7874 0.5842)
					(thickness 0.1524)
				)
				(justify mirror)
			)
		)
		(property "Device Type" "RESISTOR-G155-11003-01,100KOHMA"
			(at -0.008382 1.210564 180)
			(unlocked yes)
			(layer "B.Fab")
			(hide yes)
			(effects
				(font
					(size 0.7874 0.5842)
					(thickness 0.1524)
				)
				(justify mirror)
			)
		)
		(duplicate_pad_numbers_are_jumpers no)
		(fp_line
			(start 1.143 0.5588)
			(end -1.143 0.5588)
			(stroke
				(width 0.1)
				(type default)
			)
			(layer "B.SilkS")
		)
		(fp_line
			(start 1.143 -0.5588)
			(end 1.143 0.5588)
			(stroke
				(width 0.1)
				(type default)
			)
			(layer "B.SilkS")
		)
		(fp_line
			(start -1.143 0.5588)
			(end -1.143 -0.5588)
			(stroke
				(width 0.1)
				(type default)
			)
			(layer "B.SilkS")
		)
		(fp_line
			(start -1.143 -0.5588)
			(end 1.143 -0.5588)
			(stroke
				(width 0.1)
				(type default)
			)
			(layer "B.SilkS")
		)
		(fp_poly
			(pts
				(xy 1.143 0.5588) (xy -1.143 0.5588) (xy -1.143 -0.5588) (xy 1.143 -0.5588)
			)
			(stroke
				(width 0)
				(type default)
			)
			(fill no)
			(layer "B.CrtYd")
		)
		(fp_line
			(start 0.508 0.3048)
			(end -0.508 0.3048)
			(stroke
				(width 0.1)
				(type default)
			)
			(layer "B.Fab")
		)
		(fp_line
			(start 0.508 -0.3048)
			(end 0.508 0.3048)
			(stroke
				(width 0.1)
				(type default)
			)
			(layer "B.Fab")
		)
		(fp_line
			(start -0.508 0.3048)
			(end -0.508 -0.3048)
			(stroke
				(width 0.1)
				(type default)
			)
			(layer "B.Fab")
		)
		(fp_line
			(start -0.508 -0.3048)
			(end 0.508 -0.3048)
			(stroke
				(width 0.1)
				(type default)
			)
			(layer "B.Fab")
		)
		(pad "1" smd rect
			(at 0.5334 0)
			(size 0.7112 0.6096)
			(layers "B.Cu" "B.Mask" "B.Paste")
			(net "FT4232_I2C_SDA")
		)
		(pad "2" smd rect
			(at -0.5334 0)
			(size 0.7112 0.6096)
			(layers "B.Cu" "B.Mask" "B.Paste")
			(net "XP3R3V_FT4232")
		)
		(zone
			(layer "B.Cu")
			(hatch none 0.5)
			(connect_pads
				(clearance 0)
			)
			(min_thickness 0.25)
			(keepout
				(tracks not_allowed)
				(vias allowed)
				(pads allowed)
				(copperpour not_allowed)
				(footprints allowed)
			)
			(placement
				(enabled no)
				(sheetname "")
			)
			(fill
				(thermal_gap 0.5)
				(thermal_bridge_width 0.5)
				(island_removal_mode 0)
			)
			(polygon
				(pts
					(xy 18.3388 -81.5848) (xy 18.3388 -80.9752) (xy 18.4912 -80.9752) (xy 18.4912 -81.5848)
				)
			)
		)
		(zone
			(layer "B.Cu")
			(hatch none 0.5)
			(connect_pads
				(clearance 0)
			)
			(min_thickness 0.25)
			(keepout
				(tracks allowed)
				(vias not_allowed)
				(pads allowed)
				(copperpour not_allowed)
				(footprints allowed)
			)
			(placement
				(enabled no)
				(sheetname "")
			)
			(fill
				(thermal_gap 0.5)
				(thermal_bridge_width 0.5)
				(island_removal_mode 0)
			)
			(polygon
				(pts
					(xy 18.3388 -81.5848) (xy 18.3388 -80.9752) (xy 18.4912 -80.9752) (xy 18.4912 -81.5848)
				)
			)
		)
	)
)
